M48
INCH,TZ
T01C.01
T02C.012
T03C.04
T04C.14
T05C.044
T06C.063
T07C.065
T08C.086
;LEADER: 12 
;HEADER: 
;CODE  : ASCII 
;FILE  : 15750-1-1-8.drl for board 15750-1.brd ... layers TOP and BOTTOM
;T01 Holesize 1. = 10.000000 Tolerance = +0.000000/-0.000000 PLATED MILS Quantity = 152
;T02 Holesize 2. = 12.000000 Tolerance = +0.000000/-0.000000 PLATED MILS Quantity = 314
;T03 Holesize 3. = 40.000000 Tolerance = +0.000000/-0.000000 PLATED MILS Quantity = 3
;T04 Holesize 4. = 140.000000 Tolerance = +0.000000/-0.000000 PLATED MILS Quantity = 3
;T05 Holesize 5. = 44.000000 Tolerance = +0.000000/-0.000000 NON_PLATED MILS Quantity = 2
;T06 Holesize 6. = 63.000000 Tolerance = +0.000000/-0.000000 NON_PLATED MILS Quantity = 3
;T07 Holesize 7. = 65.000000 Tolerance = +0.000000/-0.000000 NON_PLATED MILS Quantity = 1
;T08 Holesize 8. = 86.000000 Tolerance = +0.000000/-0.000000 NON_PLATED MILS Quantity = 7
%
G90
T01
X99000Y277500
X95000
X92500Y295000
Y298500
Y309000
X91500Y312500
X96750Y313250
Y328500
X100500Y347289
Y335689
X109500Y334500
X103500Y321000
Y317000
X100250Y313200
X103750
X107000Y311500
Y308000
X108000Y303100
Y298500
Y295000
X100000Y288500
X106137Y286000
X106500Y277500
X103000
X114500Y276500
X118000
X110500Y277500
X112500Y289000
X115000Y305000
X119000
X116500Y315000
X113000Y334500
X117000
X121000
X120120Y315000
X124000
X122000Y301000
X121456Y289154
X126000Y287000
X128500Y282500
X122100Y280750
X125000Y277000
X121500Y276500
X130000Y298500
X140500Y281000
X215064Y316100
X225000Y169500
Y164250
Y160250
Y149250
X236805Y146452
X237000Y152500
Y156000
Y159780
Y164250
X236500Y168500
X251000Y197000
X258750Y168000
X251500Y164500
X252000Y160500
Y155000
Y151500
X251000Y88500
X263000Y81338
Y84838
Y88500
Y96500
X269650Y97899
X262819Y100157
X269650Y102299
X263000Y104000
X267700Y153250
X268140Y161221
X263000Y190000
Y193500
Y197000
Y205000
X269650Y206561
X262819Y208819
X269650Y210961
X263000Y212500
Y240315
X273600Y240250
X275100Y222772
X271650
X275100Y218372
X271650
X273100Y210961
Y206561
X273500Y199961
Y194055
X279000Y166000
X278860Y162250
X271250Y138750
X271650Y114110
X275100
X271650Y109710
X275100
X273100Y102299
Y97899
X295000Y86699
Y89899
X292000Y126000
X299300Y132643
Y137043
X290500Y150750
Y154250
X296500Y157500
X291000Y169500
X292000Y181500
X294750Y195261
X291300Y195361
Y198561
X294750Y198661
X302000Y157500
X302800Y137043
Y132643
X300500Y129100
X301000Y125000
X325244Y169587
Y166437
Y163288
Y160138
Y156988
Y153839
Y150689
Y147540
Y144390
Y138091
Y128642
Y119193
Y112894
Y109744
Y106595
Y103445
Y100296
Y97146
Y93996
Y90847
Y87697
Y84548
Y81398
Y78248
Y75099
Y71949
Y68799
Y65650
Y62500
Y59351
Y56201
Y53051
Y49902
T02
X255000Y5000
X270000
X282500
X295000
X315000
X345000
Y20000
X315000
X300000Y35000
Y20000
X285000Y32500
X272500Y20000
X270000Y35000
X255000
X225000
Y50000
X295500Y52000
X297500Y49000
X299500Y46000
Y52000
X301500Y49000
X303500Y46000
X315000Y40000
X304565Y61142
X300500Y61000
X296500
X280000Y71614
Y67677
X275500Y63346
X251000Y72838
Y68838
X247000Y72838
Y68838
X230000Y67000
Y75000
Y71000
X225000Y65000
Y95000
Y80000
X230000Y96500
X273000Y92283
X291500Y85393
Y97204
X291550Y91299
X304500Y92000
X304565Y96142
X295500Y100000
Y110000
X291500Y109960
Y114921
Y101960
X225000Y110000
X230000Y130000
Y134500
Y122000
Y138500
Y126000
X247000Y136338
Y123838
Y127838
X251000
Y136338
Y123838
X262920Y131653
X280169Y132637
Y138543
Y120826
Y126732
X295311Y127600
X304500Y123820
X304565Y141142
X275768Y144842
X251000Y140838
X247000
X230000Y142500
Y175500
Y179500
X247000Y177500
X251000
X275500Y172008
X280000Y176339
X313000Y179500
X280000Y180276
X251000Y181500
X247000
X230000Y183500
X225000Y205000
X291500Y218461
Y210961
Y205866
X295500Y208461
X324302Y203977
X325000Y225000
X310000
X291500Y235394
Y223583
Y229488
X251000Y236500
Y232500
X247000Y236500
Y232500
X230000Y230500
Y238500
Y234500
Y243000
Y251000
Y247000
X247000Y245000
Y249500
X251000Y245000
Y249500
X275768Y253504
X280169Y247205
X291500Y241299
X301711Y245000
X310000Y255000
Y240000
X325000Y255000
Y240000
Y270000
X310000
X295000
X280000
X265000
X249000Y260000
X100000Y270000
X85000
X70000
X55000
X40000
Y285000
X55000
X59500Y294189
Y299939
X72000Y286000
Y290000
X89000Y291189
Y299689
Y283189
Y295189
Y287189
X138500Y299500
X142500
X162311Y293000
X176311Y294000
X181061Y297750
X195811Y296000
X218000Y292000
X222911Y287089
X242500Y294000
Y298000
X246500Y294000
Y298000
X250500Y294000
Y298000
X265000Y285000
X267500Y294000
Y298000
X271500
Y294000
X275500
Y298000
X280000Y285000
X295000
X310000
X325000
X340000
Y300000
Y315000
X325000Y300000
Y315000
X310000
Y300000
X295000Y315000
Y300000
X280000
Y315000
X275500Y306000
Y302000
X271500Y306000
Y302000
X267500
Y306000
X250500Y302000
Y306000
X246500
Y302000
X242500Y306000
Y302000
X215811Y300000
X200811Y317000
Y308000
Y314000
Y311000
X189811Y310500
Y318500
Y314500
X185811
Y304200
Y318500
Y310500
X181811Y318500
Y310500
Y314500
X176168Y305500
X172311
X169811Y313500
Y309500
X164811Y304000
X160811Y310000
X155000Y301350
X150500Y303500
Y307500
X146500
Y303500
X142500
Y307500
X138500Y303500
Y307500
X134500
X89000Y303689
X75100Y315689
X71500
X67900
X64500Y309589
X58000Y310689
X40000Y300000
X10000Y330000
X40000
X52500Y331189
Y325189
X72000Y336689
X89000Y329189
Y333189
X137500Y324500
X141811
X145811
X149811
X153811
X157811
X161811
X165811
X169811
X181811Y322500
Y326500
X184500Y334000
Y338000
X185811Y322500
Y326500
X189811Y322500
Y326500
X218311Y325000
X222311
X237500Y336000
X241500
X256500
X260500
X310000Y330000
X325000
X340000
Y345000
X325000
X310000
X260500Y340000
Y344000
X256500Y340000
Y344000
X241500Y340000
Y344000
X237500Y340000
Y344000
X169811Y341500
Y345500
X165811Y341500
Y345500
X161811
Y341500
X157811
Y345500
X153811Y341500
Y345500
X149811
Y341500
X145811Y345500
Y341500
X141811
Y345500
X138000Y341500
Y345500
X79000Y348000
Y344000
X40000Y345000
X10000
Y360000
X25000
X40000
X55000
X70000
X85000
X100000
X115000
X130000
X145000
X160000
X175000
X190000
X205000
X220000
X235000
X250000
X265000
X310000
X325000
X340000
T03
X302000Y290500
Y300500
Y310500
T04
X237013Y17712
X287407Y345704
X25596Y316176
T05
X265551Y143464
Y252126
T06
X311614Y31870
X265551Y64724
Y173386
T07
X311614Y185414
T08
X26087Y-114844
X26435Y373984
X175335Y189062
Y62719
X547104Y69007
Y195351
X696192Y373984
M30
